#ISCELL
  mstr_misc prelim *
  *
#ISCELL
  mstr_symbols design_note *
  *
#ISCELL
  mstr_symbols intel_corp_bpage *
  *
#CELL
  chpset_lib skx_ext_b *
  page69_i1
#ISCELL
  mstr_symbols gnd *
  page69_i2
